(kicad_pcb
	(version 20260206)
	(generator "pcbnew")
	(generator_version "10.0")
	(general
		(thickness 1.6)
		(legacy_teardrops no)
	)
	(paper "A4")
	(title_block
		(title "04192023_DAF0TMB3IC0_F0TG_MB_C_brd_V02_OCP.brd")
		(comment 1 "Grand Teton / footprints 7434-7442 of 8354")
	)
	(layers
		(0 "F.Cu" signal "TOP")
		(4 "In1.Cu" signal "GND")
		(6 "In2.Cu" signal "IN1")
		(8 "In3.Cu" signal "GND1")
		(10 "In4.Cu" signal "IN2")
		(12 "In5.Cu" signal "GND2")
		(14 "In6.Cu" signal "IN3")
		(16 "In7.Cu" signal "GND3")
		(18 "In8.Cu" signal "VCC")
		(20 "In9.Cu" signal "VCC1")
		(22 "In10.Cu" signal "GND4")
		(24 "In11.Cu" signal "IN4")
		(26 "In12.Cu" signal "GND5")
		(28 "In13.Cu" signal "IN5")
		(30 "In14.Cu" signal "GND6")
		(32 "In15.Cu" signal "IN6")
		(34 "In16.Cu" signal "GND7")
		(2 "B.Cu" signal "BOTTOM")
		(9 "F.Adhes" user "F.Adhesive")
		(11 "B.Adhes" user "B.Adhesive")
		(13 "F.Paste" user "Package Geometry/Pastemask Top")
		(15 "B.Paste" user "Package Geometry/Pastemask Bottom")
		(5 "F.SilkS" user "Ref Des/Silkscreen Top")
		(7 "B.SilkS" user "Ref Des/Silkscreen Bottom")
		(1 "F.Mask" user "Board Geometry/Soldermask Top")
		(3 "B.Mask" user "Board Geometry/Soldermask Bottom")
		(17 "Dwgs.User" user "User.Drawings")
		(19 "Cmts.User" user "User.Comments")
		(21 "Eco1.User" user "User.Eco1")
		(23 "Eco2.User" user "User.Eco2")
		(25 "Edge.Cuts" user "Board Geometry/Outline")
		(27 "Margin" user)
		(31 "F.CrtYd" user "Package Geometry/Place Bound Top")
		(29 "B.CrtYd" user "Package Geometry/Place Bound Bottom")
		(35 "F.Fab" user "Ref Des/Assembly Top")
		(33 "B.Fab" user "Ref Des/Assembly Bottom")
	)
	(footprint ""
		(layer "B.Cu")
		(at 233.172 -337.312 180)
		(property "Reference" "R1110"
			(at 0 0 0)
			(layer "B.SilkS")
			(hide yes)
			(effects
				(font
					(size 1.27 1.27)
				)
				(justify mirror)
			)
		)
		(property "Value" ""
			(at 0 0 0)
			(layer "B.Fab")
			(effects
				(font
					(size 1.27 1.27)
				)
				(justify mirror)
			)
		)
		(duplicate_pad_numbers_are_jumpers no)
		(fp_line
			(start 0.32512 0.175006)
			(end 0.32512 -0.175006)
			(stroke
				(width 0.1)
				(type default)
			)
			(layer "B.Fab")
		)
		(fp_line
			(start 0.32512 -0.175006)
			(end -0.32512 -0.175006)
			(stroke
				(width 0.1)
				(type default)
			)
			(layer "B.Fab")
		)
		(fp_line
			(start -0.32512 0.175006)
			(end 0.32512 0.175006)
			(stroke
				(width 0.1)
				(type default)
			)
			(layer "B.Fab")
		)
		(fp_line
			(start -0.32512 -0.175006)
			(end -0.32512 0.175006)
			(stroke
				(width 0.1)
				(type default)
			)
			(layer "B.Fab")
		)
		(pad "1" smd rect
			(at 0.2667 0)
			(size 0.3048 0.381)
			(layers "B.Cu" "B.Mask" "B.Paste")
			(net "SMB_RT_CPU0_P3_R_SDA")
		)
		(pad "2" smd rect
			(at -0.2667 0 180)
			(size 0.3048 0.381)
			(layers "B.Cu" "B.Mask" "B.Paste")
			(net "SMB_RT_CPU0_P3_R2_SDA")
		)
	)
	(footprint ""
		(layer "B.Cu")
		(at 151.946102 -388.011162 -90)
		(property "Reference" "C396"
			(at 0 0 90)
			(layer "B.SilkS")
			(hide yes)
			(effects
				(font
					(size 1.27 1.27)
				)
				(justify mirror)
			)
		)
		(property "Value" ""
			(at 0 0 90)
			(layer "B.Fab")
			(effects
				(font
					(size 1.27 1.27)
				)
				(justify mirror)
			)
		)
		(duplicate_pad_numbers_are_jumpers no)
		(fp_line
			(start -0.299974 0.150114)
			(end 0.299974 0.150114)
			(stroke
				(width 0.1)
				(type default)
			)
			(layer "B.Fab")
		)
		(fp_line
			(start 0.299974 0.150114)
			(end 0.299974 -0.150114)
			(stroke
				(width 0.1)
				(type default)
			)
			(layer "B.Fab")
		)
		(fp_line
			(start -0.299974 -0.150114)
			(end -0.299974 0.150114)
			(stroke
				(width 0.1)
				(type default)
			)
			(layer "B.Fab")
		)
		(fp_line
			(start 0.299974 -0.150114)
			(end -0.299974 -0.150114)
			(stroke
				(width 0.1)
				(type default)
			)
			(layer "B.Fab")
		)
		(pad "1" smd rect
			(at 0.2667 0 90)
			(size 0.3048 0.381)
			(layers "B.Cu" "B.Mask" "B.Paste")
			(net "P0V9_CPU1_RT2_2A_2D")
		)
		(pad "2" smd rect
			(at -0.2667 0 90)
			(size 0.3048 0.381)
			(layers "B.Cu" "B.Mask" "B.Paste")
			(net "GND")
		)
	)
	(footprint ""
		(layer "B.Cu")
		(at 135.115554 -165.145212 90)
		(property "Reference" "PC355_3"
			(at 0 0 90)
			(layer "B.SilkS")
			(hide yes)
			(effects
				(font
					(size 1.27 1.27)
				)
				(justify mirror)
			)
		)
		(property "Value" ""
			(at 0 0 90)
			(layer "B.Fab")
			(effects
				(font
					(size 1.27 1.27)
				)
				(justify mirror)
			)
		)
		(duplicate_pad_numbers_are_jumpers no)
		(fp_line
			(start 1.524 -0.762)
			(end -1.524 -0.762)
			(stroke
				(width 0.1524)
				(type default)
			)
			(layer "B.SilkS")
		)
		(fp_line
			(start -1.524 -0.762)
			(end -1.524 0.762)
			(stroke
				(width 0.1524)
				(type default)
			)
			(layer "B.SilkS")
		)
		(fp_line
			(start 1.524 0.762)
			(end 1.524 -0.762)
			(stroke
				(width 0.1524)
				(type default)
			)
			(layer "B.SilkS")
		)
		(fp_line
			(start -1.524 0.762)
			(end 1.524 0.762)
			(stroke
				(width 0.1524)
				(type default)
			)
			(layer "B.SilkS")
		)
		(fp_line
			(start 1.1049 -0.724916)
			(end 1.1049 0.724916)
			(stroke
				(width 0.1)
				(type default)
			)
			(layer "B.Fab")
		)
		(fp_line
			(start -1.1049 -0.724916)
			(end 1.1049 -0.724916)
			(stroke
				(width 0.1)
				(type default)
			)
			(layer "B.Fab")
		)
		(fp_line
			(start 1.1049 0.724916)
			(end -1.1049 0.724916)
			(stroke
				(width 0.1)
				(type default)
			)
			(layer "B.Fab")
		)
		(fp_line
			(start -1.1049 0.724916)
			(end -1.1049 -0.724916)
			(stroke
				(width 0.1)
				(type default)
			)
			(layer "B.Fab")
		)
		(pad "1" smd rect
			(at 0.889 0 90)
			(size 1.016 1.27)
			(layers "B.Cu" "B.Mask" "B.Paste")
			(net "PVDDCR_SOC_P1")
		)
		(pad "2" smd rect
			(at -0.889 0 90)
			(size 1.016 1.27)
			(layers "B.Cu" "B.Mask" "B.Paste")
			(net "GND")
		)
	)
	(footprint ""
		(layer "B.Cu")
		(at 212.725 -57.061608 90)
		(property "Reference" "R4093"
			(at 0 0 90)
			(layer "B.SilkS")
			(hide yes)
			(effects
				(font
					(size 1.27 1.27)
				)
				(justify mirror)
			)
		)
		(property "Value" ""
			(at 0 0 90)
			(layer "B.Fab")
			(effects
				(font
					(size 1.27 1.27)
				)
				(justify mirror)
			)
		)
		(duplicate_pad_numbers_are_jumpers no)
		(fp_line
			(start 0.7874 -0.4064)
			(end -0.7874 -0.4064)
			(stroke
				(width 0.1524)
				(type default)
			)
			(layer "B.SilkS")
		)
		(fp_line
			(start -0.7874 -0.4064)
			(end -0.7874 0.4064)
			(stroke
				(width 0.1524)
				(type default)
			)
			(layer "B.SilkS")
		)
		(fp_line
			(start 0.7874 0.4064)
			(end 0.7874 -0.4064)
			(stroke
				(width 0.1524)
				(type default)
			)
			(layer "B.SilkS")
		)
		(fp_line
			(start -0.7874 0.4064)
			(end 0.7874 0.4064)
			(stroke
				(width 0.1524)
				(type default)
			)
			(layer "B.SilkS")
		)
		(fp_line
			(start 0.67945 -0.305054)
			(end 0.12065 -0.305054)
			(stroke
				(width 0.1)
				(type default)
			)
			(layer "B.Fab")
		)
		(fp_line
			(start 0.12065 -0.305054)
			(end 0.12065 -0.2794)
			(stroke
				(width 0.1)
				(type default)
			)
			(layer "B.Fab")
		)
		(fp_line
			(start -0.12065 -0.3048)
			(end -0.67945 -0.3048)
			(stroke
				(width 0.1)
				(type default)
			)
			(layer "B.Fab")
		)
		(fp_line
			(start -0.67945 -0.3048)
			(end -0.67945 0.3048)
			(stroke
				(width 0.1)
				(type default)
			)
			(layer "B.Fab")
		)
		(fp_line
			(start 0.12065 -0.2794)
			(end -0.12065 -0.2794)
			(stroke
				(width 0.1)
				(type default)
			)
			(layer "B.Fab")
		)
		(fp_line
			(start -0.12065 -0.2794)
			(end -0.12065 -0.3048)
			(stroke
				(width 0.1)
				(type default)
			)
			(layer "B.Fab")
		)
		(fp_line
			(start 0.12065 0.2794)
			(end 0.12065 0.3048)
			(stroke
				(width 0.1)
				(type default)
			)
			(layer "B.Fab")
		)
		(fp_line
			(start -0.120396 0.2794)
			(end 0.12065 0.2794)
			(stroke
				(width 0.1)
				(type default)
			)
			(layer "B.Fab")
		)
		(fp_line
			(start 0.67945 0.3048)
			(end 0.67945 -0.305054)
			(stroke
				(width 0.1)
				(type default)
			)
			(layer "B.Fab")
		)
		(fp_line
			(start 0.12065 0.3048)
			(end 0.67945 0.3048)
			(stroke
				(width 0.1)
				(type default)
			)
			(layer "B.Fab")
		)
		(fp_line
			(start -0.120396 0.3048)
			(end -0.120396 0.2794)
			(stroke
				(width 0.1)
				(type default)
			)
			(layer "B.Fab")
		)
		(fp_line
			(start -0.67945 0.3048)
			(end -0.120396 0.3048)
			(stroke
				(width 0.1)
				(type default)
			)
			(layer "B.Fab")
		)
		(pad "1" smd circle
			(at 0.40005 0 270)
			(size 0 0)
			(layers "B.Cu" "B.Mask" "B.Paste")
			(net "P3V3_AUX")
		)
		(pad "2" smd circle
			(at -0.40005 0 270)
			(size 0 0)
			(layers "B.Cu" "B.Mask" "B.Paste")
			(net "E1S_0_P3V3_ADC_ALERT_R")
		)
	)
	(footprint ""
		(layer "B.Cu")
		(at 24.765 -364.617 180)
		(property "Reference" "R8235"
			(at 0 0 0)
			(layer "B.SilkS")
			(hide yes)
			(effects
				(font
					(size 1.27 1.27)
				)
				(justify mirror)
			)
		)
		(property "Value" ""
			(at 0 0 0)
			(layer "B.Fab")
			(effects
				(font
					(size 1.27 1.27)
				)
				(justify mirror)
			)
		)
		(duplicate_pad_numbers_are_jumpers no)
		(fp_line
			(start 0.7874 0.4064)
			(end 0.7874 -0.4064)
			(stroke
				(width 0.1524)
				(type default)
			)
			(layer "B.SilkS")
		)
		(fp_line
			(start 0.7874 -0.4064)
			(end -0.7874 -0.4064)
			(stroke
				(width 0.1524)
				(type default)
			)
			(layer "B.SilkS")
		)
		(fp_line
			(start -0.7874 0.4064)
			(end 0.7874 0.4064)
			(stroke
				(width 0.1524)
				(type default)
			)
			(layer "B.SilkS")
		)
		(fp_line
			(start -0.7874 -0.4064)
			(end -0.7874 0.4064)
			(stroke
				(width 0.1524)
				(type default)
			)
			(layer "B.SilkS")
		)
		(fp_line
			(start 0.67945 0.3048)
			(end 0.67945 -0.305054)
			(stroke
				(width 0.1)
				(type default)
			)
			(layer "B.Fab")
		)
		(fp_line
			(start 0.67945 -0.305054)
			(end 0.12065 -0.305054)
			(stroke
				(width 0.1)
				(type default)
			)
			(layer "B.Fab")
		)
		(fp_line
			(start 0.12065 0.3048)
			(end 0.67945 0.3048)
			(stroke
				(width 0.1)
				(type default)
			)
			(layer "B.Fab")
		)
		(fp_line
			(start 0.12065 0.2794)
			(end 0.12065 0.3048)
			(stroke
				(width 0.1)
				(type default)
			)
			(layer "B.Fab")
		)
		(fp_line
			(start 0.12065 -0.2794)
			(end -0.12065 -0.2794)
			(stroke
				(width 0.1)
				(type default)
			)
			(layer "B.Fab")
		)
		(fp_line
			(start 0.12065 -0.305054)
			(end 0.12065 -0.2794)
			(stroke
				(width 0.1)
				(type default)
			)
			(layer "B.Fab")
		)
		(fp_line
			(start -0.120396 0.3048)
			(end -0.120396 0.2794)
			(stroke
				(width 0.1)
				(type default)
			)
			(layer "B.Fab")
		)
		(fp_line
			(start -0.120396 0.2794)
			(end 0.12065 0.2794)
			(stroke
				(width 0.1)
				(type default)
			)
			(layer "B.Fab")
		)
		(fp_line
			(start -0.12065 -0.2794)
			(end -0.12065 -0.3048)
			(stroke
				(width 0.1)
				(type default)
			)
			(layer "B.Fab")
		)
		(fp_line
			(start -0.12065 -0.3048)
			(end -0.67945 -0.3048)
			(stroke
				(width 0.1)
				(type default)
			)
			(layer "B.Fab")
		)
		(fp_line
			(start -0.67945 0.3048)
			(end -0.120396 0.3048)
			(stroke
				(width 0.1)
				(type default)
			)
			(layer "B.Fab")
		)
		(fp_line
			(start -0.67945 -0.3048)
			(end -0.67945 0.3048)
			(stroke
				(width 0.1)
				(type default)
			)
			(layer "B.Fab")
		)
		(pad "1" smd circle
			(at 0.40005 0)
			(size 0 0)
			(layers "B.Cu" "B.Mask" "B.Paste")
			(net "FM_PVDDCR_CPU1_P1_EN")
		)
		(pad "2" smd circle
			(at -0.40005 0)
			(size 0 0)
			(layers "B.Cu" "B.Mask" "B.Paste")
			(net "PVDDCR_CPU1_P1_EN_R")
		)
	)
	(footprint ""
		(layer "B.Cu")
		(at 53.278024 -408.517344 90)
		(property "Reference" "C6663"
			(at 0 0 90)
			(layer "B.SilkS")
			(hide yes)
			(effects
				(font
					(size 1.27 1.27)
				)
				(justify mirror)
			)
		)
		(property "Value" ""
			(at 0 0 90)
			(layer "B.Fab")
			(effects
				(font
					(size 1.27 1.27)
				)
				(justify mirror)
			)
		)
		(duplicate_pad_numbers_are_jumpers no)
		(fp_line
			(start 0.299974 -0.150114)
			(end -0.299974 -0.150114)
			(stroke
				(width 0.1)
				(type default)
			)
			(layer "B.Fab")
		)
		(fp_line
			(start -0.299974 -0.150114)
			(end -0.299974 0.150114)
			(stroke
				(width 0.1)
				(type default)
			)
			(layer "B.Fab")
		)
		(fp_line
			(start 0.299974 0.150114)
			(end 0.299974 -0.150114)
			(stroke
				(width 0.1)
				(type default)
			)
			(layer "B.Fab")
		)
		(fp_line
			(start -0.299974 0.150114)
			(end 0.299974 0.150114)
			(stroke
				(width 0.1)
				(type default)
			)
			(layer "B.Fab")
		)
		(pad "1" smd rect
			(at 0.2667 0 270)
			(size 0.3048 0.381)
			(layers "B.Cu" "B.Mask" "B.Paste")
			(net "P5E_CPU1_P1_TX_BUF_C_DP<1>")
		)
		(pad "2" smd rect
			(at -0.2667 0 270)
			(size 0.3048 0.381)
			(layers "B.Cu" "B.Mask" "B.Paste")
			(net "P5E_CPU1_P1_TX_BUF_DP<1>")
		)
	)
	(footprint ""
		(layer "B.Cu")
		(at 305.423316 -427.2788 180)
		(property "Reference" "R1438"
			(at 0 0 0)
			(layer "B.SilkS")
			(hide yes)
			(effects
				(font
					(size 1.27 1.27)
				)
				(justify mirror)
			)
		)
		(property "Value" ""
			(at 0 0 0)
			(layer "B.Fab")
			(effects
				(font
					(size 1.27 1.27)
				)
				(justify mirror)
			)
		)
		(duplicate_pad_numbers_are_jumpers no)
		(fp_line
			(start 0.32512 0.175006)
			(end 0.32512 -0.175006)
			(stroke
				(width 0.1)
				(type default)
			)
			(layer "B.Fab")
		)
		(fp_line
			(start 0.32512 -0.175006)
			(end -0.32512 -0.175006)
			(stroke
				(width 0.1)
				(type default)
			)
			(layer "B.Fab")
		)
		(fp_line
			(start -0.32512 0.175006)
			(end 0.32512 0.175006)
			(stroke
				(width 0.1)
				(type default)
			)
			(layer "B.Fab")
		)
		(fp_line
			(start -0.32512 -0.175006)
			(end -0.32512 0.175006)
			(stroke
				(width 0.1)
				(type default)
			)
			(layer "B.Fab")
		)
		(pad "1" smd rect
			(at 0.2667 0)
			(size 0.3048 0.381)
			(layers "B.Cu" "B.Mask" "B.Paste")
			(net "P1V8_CPU0_RT_1D")
		)
		(pad "2" smd rect
			(at -0.2667 0 180)
			(size 0.3048 0.381)
			(layers "B.Cu" "B.Mask" "B.Paste")
			(net "JTAG_TDI_RT_CPU0_P0")
		)
	)
	(footprint ""
		(layer "B.Cu")
		(at 146.010884 -320.525902 180)
		(property "Reference" "R1502"
			(at 0 0 0)
			(layer "B.SilkS")
			(hide yes)
			(effects
				(font
					(size 1.27 1.27)
				)
				(justify mirror)
			)
		)
		(property "Value" ""
			(at 0 0 0)
			(layer "B.Fab")
			(effects
				(font
					(size 1.27 1.27)
				)
				(justify mirror)
			)
		)
		(duplicate_pad_numbers_are_jumpers no)
		(fp_line
			(start 0.7874 0.4064)
			(end 0.7874 -0.4064)
			(stroke
				(width 0.1524)
				(type default)
			)
			(layer "B.SilkS")
		)
		(fp_line
			(start 0.7874 -0.4064)
			(end -0.7874 -0.4064)
			(stroke
				(width 0.1524)
				(type default)
			)
			(layer "B.SilkS")
		)
		(fp_line
			(start -0.7874 0.4064)
			(end 0.7874 0.4064)
			(stroke
				(width 0.1524)
				(type default)
			)
			(layer "B.SilkS")
		)
		(fp_line
			(start -0.7874 -0.4064)
			(end -0.7874 0.4064)
			(stroke
				(width 0.1524)
				(type default)
			)
			(layer "B.SilkS")
		)
		(fp_line
			(start 0.67945 0.3048)
			(end 0.67945 -0.305054)
			(stroke
				(width 0.1)
				(type default)
			)
			(layer "B.Fab")
		)
		(fp_line
			(start 0.67945 -0.305054)
			(end 0.12065 -0.305054)
			(stroke
				(width 0.1)
				(type default)
			)
			(layer "B.Fab")
		)
		(fp_line
			(start 0.12065 0.3048)
			(end 0.67945 0.3048)
			(stroke
				(width 0.1)
				(type default)
			)
			(layer "B.Fab")
		)
		(fp_line
			(start 0.12065 0.2794)
			(end 0.12065 0.3048)
			(stroke
				(width 0.1)
				(type default)
			)
			(layer "B.Fab")
		)
		(fp_line
			(start 0.12065 -0.2794)
			(end -0.12065 -0.2794)
			(stroke
				(width 0.1)
				(type default)
			)
			(layer "B.Fab")
		)
		(fp_line
			(start 0.12065 -0.305054)
			(end 0.12065 -0.2794)
			(stroke
				(width 0.1)
				(type default)
			)
			(layer "B.Fab")
		)
		(fp_line
			(start -0.120396 0.3048)
			(end -0.120396 0.2794)
			(stroke
				(width 0.1)
				(type default)
			)
			(layer "B.Fab")
		)
		(fp_line
			(start -0.120396 0.2794)
			(end 0.12065 0.2794)
			(stroke
				(width 0.1)
				(type default)
			)
			(layer "B.Fab")
		)
		(fp_line
			(start -0.12065 -0.2794)
			(end -0.12065 -0.3048)
			(stroke
				(width 0.1)
				(type default)
			)
			(layer "B.Fab")
		)
		(fp_line
			(start -0.12065 -0.3048)
			(end -0.67945 -0.3048)
			(stroke
				(width 0.1)
				(type default)
			)
			(layer "B.Fab")
		)
		(fp_line
			(start -0.67945 0.3048)
			(end -0.120396 0.3048)
			(stroke
				(width 0.1)
				(type default)
			)
			(layer "B.Fab")
		)
		(fp_line
			(start -0.67945 -0.3048)
			(end -0.67945 0.3048)
			(stroke
				(width 0.1)
				(type default)
			)
			(layer "B.Fab")
		)
		(pad "1" smd circle
			(at 0.40005 0)
			(size 0 0)
			(layers "B.Cu" "B.Mask" "B.Paste")
			(net "GND")
		)
		(pad "2" smd circle
			(at -0.40005 0)
			(size 0 0)
			(layers "B.Cu" "B.Mask" "B.Paste")
			(net "CLK_CPU1_RTCCLK")
		)
	)
	(footprint ""
		(layer "B.Cu")
		(at 191.192912 -70.459346)
		(property "Reference" "R82"
			(at 0 0 0)
			(layer "B.SilkS")
			(hide yes)
			(effects
				(font
					(size 1.27 1.27)
				)
				(justify mirror)
			)
		)
		(property "Value" ""
			(at 0 0 0)
			(layer "B.Fab")
			(effects
				(font
					(size 1.27 1.27)
				)
				(justify mirror)
			)
		)
		(duplicate_pad_numbers_are_jumpers no)
		(fp_line
			(start -0.7874 -0.4064)
			(end -0.7874 0.4064)
			(stroke
				(width 0.1524)
				(type default)
			)
			(layer "B.SilkS")
		)
		(fp_line
			(start -0.7874 0.4064)
			(end 0.7874 0.4064)
			(stroke
				(width 0.1524)
				(type default)
			)
			(layer "B.SilkS")
		)
		(fp_line
			(start 0.7874 -0.4064)
			(end -0.7874 -0.4064)
			(stroke
				(width 0.1524)
				(type default)
			)
			(layer "B.SilkS")
		)
		(fp_line
			(start 0.7874 0.4064)
			(end 0.7874 -0.4064)
			(stroke
				(width 0.1524)
				(type default)
			)
			(layer "B.SilkS")
		)
		(fp_line
			(start -0.67945 -0.3048)
			(end -0.67945 0.3048)
			(stroke
				(width 0.1)
				(type default)
			)
			(layer "B.Fab")
		)
		(fp_line
			(start -0.67945 0.3048)
			(end -0.120396 0.3048)
			(stroke
				(width 0.1)
				(type default)
			)
			(layer "B.Fab")
		)
		(fp_line
			(start -0.12065 -0.3048)
			(end -0.67945 -0.3048)
			(stroke
				(width 0.1)
				(type default)
			)
			(layer "B.Fab")
		)
		(fp_line
			(start -0.12065 -0.2794)
			(end -0.12065 -0.3048)
			(stroke
				(width 0.1)
				(type default)
			)
			(layer "B.Fab")
		)
		(fp_line
			(start -0.120396 0.2794)
			(end 0.12065 0.2794)
			(stroke
				(width 0.1)
				(type default)
			)
			(layer "B.Fab")
		)
		(fp_line
			(start -0.120396 0.3048)
			(end -0.120396 0.2794)
			(stroke
				(width 0.1)
				(type default)
			)
			(layer "B.Fab")
		)
		(fp_line
			(start 0.12065 -0.305054)
			(end 0.12065 -0.2794)
			(stroke
				(width 0.1)
				(type default)
			)
			(layer "B.Fab")
		)
		(fp_line
			(start 0.12065 -0.2794)
			(end -0.12065 -0.2794)
			(stroke
				(width 0.1)
				(type default)
			)
			(layer "B.Fab")
		)
		(fp_line
			(start 0.12065 0.2794)
			(end 0.12065 0.3048)
			(stroke
				(width 0.1)
				(type default)
			)
			(layer "B.Fab")
		)
		(fp_line
			(start 0.12065 0.3048)
			(end 0.67945 0.3048)
			(stroke
				(width 0.1)
				(type default)
			)
			(layer "B.Fab")
		)
		(fp_line
			(start 0.67945 -0.305054)
			(end 0.12065 -0.305054)
			(stroke
				(width 0.1)
				(type default)
			)
			(layer "B.Fab")
		)
		(fp_line
			(start 0.67945 0.3048)
			(end 0.67945 -0.305054)
			(stroke
				(width 0.1)
				(type default)
			)
			(layer "B.Fab")
		)
		(pad "1" smd circle
			(at 0.40005 0 180)
			(size 0 0)
			(layers "B.Cu" "B.Mask" "B.Paste")
			(net "RMII_BMC_OCP_TX_EN")
		)
		(pad "2" smd circle
			(at -0.40005 0 180)
			(size 0 0)
			(layers "B.Cu" "B.Mask" "B.Paste")
			(net "GND")
		)
	)
)
